(kicad_pcb
	(version 20260206)
	(generator "pcbnew")
	(generator_version "10.0")
	(general
		(thickness 1.6)
		(legacy_teardrops no)
	)
	(paper "A4")
	(title_block
		(title "Bryce Canyon_SCC_16316-1_OCP.brd")
		(comment 1 "Bryce Canyon / footprints 63-63 of 1561")
	)
	(layers
		(0 "F.Cu" signal "TOP")
		(4 "In1.Cu" signal "L2GND")
		(6 "In2.Cu" signal "L3")
		(8 "In3.Cu" signal "L4VCC")
		(10 "In4.Cu" signal "L5VCC")
		(12 "In5.Cu" signal "L6")
		(14 "In6.Cu" signal "L7GND")
		(2 "B.Cu" signal "BOTTOM")
		(9 "F.Adhes" user "F.Adhesive")
		(11 "B.Adhes" user "B.Adhesive")
		(13 "F.Paste" user "Package Geometry/Pastemask Top")
		(15 "B.Paste" user "Package Geometry/Pastemask Bottom")
		(5 "F.SilkS" user "Ref Des/Silkscreen Top")
		(7 "B.SilkS" user "Ref Des/Silkscreen Bottom")
		(1 "F.Mask" user "Board Geometry/Soldermask Top")
		(3 "B.Mask" user "Board Geometry/Soldermask Bottom")
		(17 "Dwgs.User" user "User.Drawings")
		(19 "Cmts.User" user "User.Comments")
		(21 "Eco1.User" user "User.Eco1")
		(23 "Eco2.User" user "User.Eco2")
		(25 "Edge.Cuts" user "Board Geometry/Outline")
		(27 "Margin" user)
		(31 "F.CrtYd" user "Package Geometry/Place Bound Top")
		(29 "B.CrtYd" user "Package Geometry/Place Bound Bottom")
		(35 "F.Fab" user "Ref Des/Assembly Top")
		(33 "B.Fab" user "Ref Des/Assembly Bottom")
	)
	(footprint ""
		(layer "F.Cu")
		(at 16.637 -94.9452 180)
		(property "Reference" "R411"
			(at 0 0 180)
			(layer "F.SilkS")
			(hide yes)
			(effects
				(font
					(size 1.27 1.27)
				)
			)
		)
		(property "Value" "200KR2F-L-GP"
			(at 0.064008 -3.993896 180)
			(unlocked yes)
			(layer "F.Fab")
			(hide yes)
			(effects
				(font
					(size 1.016 1.016)
					(thickness 0.1524)
				)
			)
		)
		(property "Device Type" "R402H16"
			(at 0.064008 -5.517896 180)
			(unlocked yes)
			(layer "F.Fab")
			(hide yes)
			(effects
				(font
					(size 1.016 1.016)
					(thickness 0.1524)
				)
			)
		)
		(duplicate_pad_numbers_are_jumpers no)
		(fp_line
			(start 0.508 -0.9398)
			(end -0.508 -0.9398)
			(stroke
				(width 0.1524)
				(type default)
			)
			(layer "F.SilkS")
		)
		(fp_line
			(start -0.508 -0.9398)
			(end -0.508 0.9398)
			(stroke
				(width 0.1524)
				(type default)
			)
			(layer "F.SilkS")
		)
		(fp_rect
			(start -0.508 0.9398)
			(end 0.508 -0.9398)
			(stroke
				(width 0)
				(type default)
			)
			(fill no)
			(layer "F.CrtYd")
		)
		(fp_rect
			(start -0.508 0.9398)
			(end 0.508 -0.9398)
			(stroke
				(width 0)
				(type default)
			)
			(fill no)
			(layer "F.Fab")
		)
		(pad "1" smd custom
			(at 0 -0.4445 180)
			(size 0.1397 0.1397)
			(layers "F.Cu" "F.Mask" "F.Paste")
			(net "LS_EN_U35")
			(options
				(clearance outline)
				(anchor circle)
			)
			(primitives
				(gr_poly
					(pts
						(arc
							(start -0.1778 -0.2794)
							(mid -0.249642 -0.249642)
							(end -0.2794 -0.1778)
						)
						(arc
							(start -0.2794 0.1778)
							(mid -0.249642 0.249642)
							(end -0.1778 0.2794)
						)
						(arc
							(start 0.1778 0.2794)
							(mid 0.249642 0.249642)
							(end 0.2794 0.1778)
						)
						(arc
							(start 0.2794 -0.1778)
							(mid 0.249642 -0.249642)
							(end 0.1778 -0.2794)
						)
					)
					(width 0)
					(fill yes)
				)
			)
		)
		(pad "2" smd custom
			(at 0 0.4445 180)
			(size 0.1397 0.1397)
			(layers "F.Cu" "F.Mask" "F.Paste")
			(net "P0V9_PG")
			(options
				(clearance outline)
				(anchor circle)
			)
			(primitives
				(gr_poly
					(pts
						(arc
							(start -0.1778 -0.2794)
							(mid -0.249642 -0.249642)
							(end -0.2794 -0.1778)
						)
						(arc
							(start -0.2794 0.1778)
							(mid -0.249642 0.249642)
							(end -0.1778 0.2794)
						)
						(arc
							(start 0.1778 0.2794)
							(mid 0.249642 0.249642)
							(end 0.2794 0.1778)
						)
						(arc
							(start 0.2794 -0.1778)
							(mid 0.249642 -0.249642)
							(end 0.1778 -0.2794)
						)
					)
					(width 0)
					(fill yes)
				)
			)
		)
	)
)
